(kicad_pcb
	(version 20241229)
	(generator "pcbnew")
	(generator_version "9.0")
	(general
		(thickness 1.711)
		(legacy_teardrops no)
	)
	(paper "A4")
	(title_block
		(title "Antmicro Baseboard for Jetson AGX Thor")
		(date "2026-02-18")
		(rev "1.1.0")
		(company "Antmicro Ltd")
		(comment 1 "www.antmicro.com")
		(comment 9 "footprints 77-80 of 1170")
	)
	(layers
		(0 "F.Cu" signal)
		(4 "In1.Cu" signal)
		(6 "In2.Cu" signal)
		(8 "In3.Cu" signal)
		(10 "In4.Cu" jumper)
		(12 "In5.Cu" signal)
		(14 "In6.Cu" signal)
		(16 "In7.Cu" signal)
		(18 "In8.Cu" signal)
		(2 "B.Cu" signal)
		(9 "F.Adhes" user "F.Adhesive")
		(11 "B.Adhes" user "B.Adhesive")
		(13 "F.Paste" user)
		(15 "B.Paste" user)
		(5 "F.SilkS" user "F.Silkscreen")
		(7 "B.SilkS" user "B.Silkscreen")
		(1 "F.Mask" user)
		(3 "B.Mask" user)
		(17 "Dwgs.User" user "User.Drawings")
		(19 "Cmts.User" user "User.Comments")
		(21 "Eco1.User" user "User.Eco1")
		(23 "Eco2.User" user "User.Eco2")
		(25 "Edge.Cuts" user)
		(27 "Margin" user)
		(31 "F.CrtYd" user "F.Courtyard")
		(29 "B.CrtYd" user "B.Courtyard")
		(35 "F.Fab" user)
		(33 "B.Fab" user)
	)
	(footprint "antmicro-footprints:R_0805_2012Metric"
		(layer "F.Cu")
		(at 162.944468 96.225 180)
		(property "Reference" "R65"
			(at 1.944468 0.925 0)
			(layer "F.SilkS")
			(effects
				(font
					(size 0.7 0.7)
					(thickness 0.15)
				)
				(justify right top)
			)
		)
		(property "Value" "R_0R001_0805"
			(at 0 1.8 0)
			(layer "F.Fab")
			(effects
				(font
					(size 0.7 0.7)
					(thickness 0.15)
				)
				(justify right top)
			)
		)
		(property "Datasheet" "https://www.eaton.com/content/dam/eaton/products/electronic-components/resources/data-sheet/eaton-msma-automotive-smd-current-sense-resistor-metal-strip-data-sheet-elx1179.pdf"
			(at 0 0 0)
			(layer "F.Fab")
			(hide yes)
			(effects
				(font
					(size 1.27 1.27)
					(thickness 0.15)
				)
			)
		)
		(property "Description" "Current Sense Resistors - SMD MSMA, 0805 SIZE, 1/2 Watt, 1 mohm, 50 TCR MnCu Metal AEC-Q"
			(at 0 0 0)
			(layer "F.Fab")
			(hide yes)
			(effects
				(font
					(size 1.27 1.27)
					(thickness 0.15)
				)
			)
		)
		(property "MPN" "MSMA0805R0010FSM"
			(at 0 0 180)
			(unlocked yes)
			(layer "F.Fab")
			(hide yes)
			(effects
				(font
					(size 1 1)
					(thickness 0.15)
				)
			)
		)
		(property "Manufacturer" "Eaton"
			(at 0 0 180)
			(unlocked yes)
			(layer "F.Fab")
			(hide yes)
			(effects
				(font
					(size 1 1)
					(thickness 0.15)
				)
			)
		)
		(property "License" "Apache-2.0"
			(at 0 0 180)
			(unlocked yes)
			(layer "F.Fab")
			(hide yes)
			(effects
				(font
					(size 1 1)
					(thickness 0.15)
				)
			)
		)
		(property "Author" "Antmicro"
			(at 0 0 180)
			(unlocked yes)
			(layer "F.Fab")
			(hide yes)
			(effects
				(font
					(size 1 1)
					(thickness 0.15)
				)
			)
		)
		(property "Val" "0R001"
			(at 0 0 180)
			(unlocked yes)
			(layer "F.Fab")
			(hide yes)
			(effects
				(font
					(size 1 1)
					(thickness 0.15)
				)
			)
		)
		(property "Tolerance" "1%"
			(at 0 0 180)
			(unlocked yes)
			(layer "F.Fab")
			(hide yes)
			(effects
				(font
					(size 1 1)
					(thickness 0.15)
				)
			)
		)
		(property "Public" "False"
			(at 0 0 180)
			(unlocked yes)
			(layer "F.Fab")
			(hide yes)
			(effects
				(font
					(size 1 1)
					(thickness 0.15)
				)
			)
		)
		(component_classes
			(class "DCDC_SOM")
		)
		(sheetname "/DCDC/")
		(sheetfile "dcdc.kicad_sch")
		(attr smd)
		(fp_line
			(start -0.3 -0.701)
			(end 0.298 -0.701)
			(stroke
				(width 0.15)
				(type solid)
			)
			(layer "F.SilkS")
		)
		(fp_line
			(start -0.32 0.699)
			(end 0.28 0.699)
			(stroke
				(width 0.15)
				(type solid)
			)
			(layer "F.SilkS")
		)
		(fp_rect
			(start 1.95 -0.9)
			(end -1.95 0.9)
			(stroke
				(width 0.05)
				(type default)
			)
			(fill no)
			(layer "F.CrtYd")
		)
		(fp_line
			(start 0.949 -0.677)
			(end 0.949 0.675)
			(stroke
				(width 0.15)
				(type solid)
			)
			(layer "F.Fab")
		)
		(fp_line
			(start -0.951 0.68)
			(end 0.949 0.68)
			(stroke
				(width 0.15)
				(type solid)
			)
			(layer "F.Fab")
		)
		(fp_line
			(start -0.951 -0.677)
			(end -0.951 0.675)
			(stroke
				(width 0.15)
				(type solid)
			)
			(layer "F.Fab")
		)
		(fp_line
			(start -0.951 -0.682)
			(end 0.949 -0.682)
			(stroke
				(width 0.15)
				(type solid)
			)
			(layer "F.Fab")
		)
		(fp_text user "Author: Antmicro"
			(at -1.9 4.4 0)
			(layer "F.Fab")
			(effects
				(font
					(size 0.7 0.7)
					(thickness 0.15)
				)
				(justify right top)
			)
		)
		(fp_text user "License: Apache-2.0"
			(at -1.9 5.75 0)
			(layer "F.Fab")
			(effects
				(font
					(size 0.7 0.7)
					(thickness 0.15)
				)
				(justify right top)
			)
		)
		(fp_text user "${REFERENCE}"
			(at -1.9 3.1 0)
			(layer "F.Fab")
			(effects
				(font
					(size 0.7 0.7)
					(thickness 0.15)
				)
				(justify right top)
			)
		)
		(pad "1" smd roundrect
			(at -1.1 0 180)
			(size 1.2 1.3)
			(layers "F.Cu" "F.Mask" "F.Paste")
			(roundrect_rratio 0.25)
			(net 903 "/DCDC/16V_OUT")
			(pintype "passive")
		)
		(pad "2" smd roundrect
			(at 1.1 0 180)
			(size 1.2 1.3)
			(layers "F.Cu" "F.Mask" "F.Paste")
			(roundrect_rratio 0.25)
			(net 12 "SYS_VIN_HV")
			(pintype "passive")
		)
	)
	(footprint "antmicro-footprints:SOT-563"
		(layer "F.Cu")
		(at 190.08 127.36 90)
		(property "Reference" "U69"
			(at -0.94 -3.78 90)
			(layer "F.SilkS")
			(effects
				(font
					(size 0.7 0.7)
					(thickness 0.15)
				)
				(justify left bottom)
			)
		)
		(property "Value" "TPS564247DRLR"
			(at 0 2 90)
			(layer "F.Fab")
			(effects
				(font
					(size 0.7 0.7)
					(thickness 0.15)
				)
				(justify left bottom)
			)
		)
		(property "Datasheet" "https://www.ti.com/lit/ds/symlink/tps564247.pdf?ts=1713526387938&ref_url=https%253A%252F%252Fwww.mouser.pl%252F"
			(at 0 0 90)
			(layer "F.Fab")
			(hide yes)
			(effects
				(font
					(size 1.27 1.27)
					(thickness 0.15)
				)
			)
		)
		(property "Description" "Switching Voltage Regulators 3-V to 16-V input voltage, 4-A FCCM mode, synchronous buck converter in SOT-563 package 6-SOT-5X3 -40 to 125"
			(at 0 0 90)
			(layer "F.Fab")
			(hide yes)
			(effects
				(font
					(size 1.27 1.27)
					(thickness 0.15)
				)
			)
		)
		(property "MPN" "TPS564247DRLR"
			(at 0 0 90)
			(unlocked yes)
			(layer "F.Fab")
			(hide yes)
			(effects
				(font
					(size 1 1)
					(thickness 0.15)
				)
			)
		)
		(property "Author" "Antmicro"
			(at 0 0 90)
			(unlocked yes)
			(layer "F.Fab")
			(hide yes)
			(effects
				(font
					(size 1 1)
					(thickness 0.15)
				)
			)
		)
		(property "License" "Apache-2.0"
			(at 0 0 90)
			(unlocked yes)
			(layer "F.Fab")
			(hide yes)
			(effects
				(font
					(size 1 1)
					(thickness 0.15)
				)
			)
		)
		(property "Manufacturer" "Texas Instruments"
			(at 0 0 90)
			(unlocked yes)
			(layer "F.Fab")
			(hide yes)
			(effects
				(font
					(size 1 1)
					(thickness 0.15)
				)
			)
		)
		(component_classes
			(class "DCDC_1V15")
		)
		(sheetname "/DCDC/")
		(sheetfile "dcdc.kicad_sch")
		(attr smd)
		(fp_line
			(start 0.776 -0.974)
			(end 0.526 -0.974)
			(stroke
				(width 0.15)
				(type solid)
			)
			(layer "F.SilkS")
		)
		(fp_line
			(start 0.776 -0.974)
			(end 0.776 -0.778)
			(stroke
				(width 0.15)
				(type solid)
			)
			(layer "F.SilkS")
		)
		(fp_line
			(start -0.499 -0.974)
			(end -0.724 -0.778)
			(stroke
				(width 0.15)
				(type solid)
			)
			(layer "F.SilkS")
		)
		(fp_line
			(start 0.776 0.776)
			(end 0.776 0.972)
			(stroke
				(width 0.15)
				(type solid)
			)
			(layer "F.SilkS")
		)
		(fp_line
			(start -0.778 0.776)
			(end -0.778 0.949)
			(stroke
				(width 0.15)
				(type solid)
			)
			(layer "F.SilkS")
		)
		(fp_line
			(start -0.778 0.949)
			(end -0.424 0.949)
			(stroke
				(width 0.15)
				(type solid)
			)
			(layer "F.SilkS")
		)
		(fp_line
			(start 0.776 0.972)
			(end 0.526 0.972)
			(stroke
				(width 0.15)
				(type solid)
			)
			(layer "F.SilkS")
		)
		(fp_circle
			(center -0.903 -0.999)
			(end -0.952 -0.95)
			(stroke
				(width 0.15)
				(type solid)
			)
			(fill yes)
			(layer "F.SilkS")
		)
		(fp_rect
			(start 1.19 -1.12)
			(end -1.2 1.1)
			(stroke
				(width 0.05)
				(type solid)
			)
			(fill no)
			(layer "F.CrtYd")
		)
		(fp_line
			(start 0.651 -0.849)
			(end 0.651 0.847)
			(stroke
				(width 0.15)
				(type solid)
			)
			(layer "F.Fab")
		)
		(fp_line
			(start -0.453 -0.849)
			(end 0.651 -0.849)
			(stroke
				(width 0.15)
				(type solid)
			)
			(layer "F.Fab")
		)
		(fp_line
			(start -0.453 -0.849)
			(end -0.653 -0.678)
			(stroke
				(width 0.15)
				(type solid)
			)
			(layer "F.Fab")
		)
		(fp_line
			(start -0.653 -0.678)
			(end -0.653 0.847)
			(stroke
				(width 0.15)
				(type solid)
			)
			(layer "F.Fab")
		)
		(fp_line
			(start 0.651 0.847)
			(end -0.653 0.847)
			(stroke
				(width 0.15)
				(type solid)
			)
			(layer "F.Fab")
		)
		(fp_text user "License: Apache-2.0"
			(at -1.299 4.924 90)
			(layer "F.Fab")
			(effects
				(font
					(size 0.7 0.7)
					(thickness 0.15)
				)
				(justify left bottom)
			)
		)
		(fp_text user "Author: Antmicro"
			(at -1.299 6.124 90)
			(layer "F.Fab")
			(effects
				(font
					(size 0.7 0.7)
					(thickness 0.15)
				)
				(justify left bottom)
			)
		)
		(fp_text user "${REFERENCE}"
			(at -1.299 7.323 90)
			(layer "F.Fab")
			(effects
				(font
					(size 0.7 0.7)
					(thickness 0.15)
				)
				(justify left bottom)
			)
		)
		(pad "1" smd roundrect
			(at -0.749 -0.499)
			(size 0.3 0.6)
			(layers "F.Cu" "F.Mask" "F.Paste")
			(roundrect_rratio 0.25)
			(net 5 "+5V")
			(pinfunction "V_{IN}")
			(pintype "power_in")
		)
		(pad "2" smd roundrect
			(at -0.749 0.001)
			(size 0.3 0.6)
			(layers "F.Cu" "F.Mask" "F.Paste")
			(roundrect_rratio 0.25)
			(net 1034 "/DCDC/1V15_SW")
			(pinfunction "SW")
			(pintype "passive")
		)
		(pad "3" smd roundrect
			(at -0.749 0.497)
			(size 0.3 0.6)
			(layers "F.Cu" "F.Mask" "F.Paste")
			(roundrect_rratio 0.25)
			(net 1 "GND")
			(pinfunction "GND")
			(pintype "power_in")
		)
		(pad "4" smd roundrect
			(at 0.747 0.497)
			(size 0.3 0.6)
			(layers "F.Cu" "F.Mask" "F.Paste")
			(roundrect_rratio 0.25)
			(net 1 "GND")
			(pinfunction "AGND")
			(pintype "power_in")
		)
		(pad "5" smd roundrect
			(at 0.747 0.001)
			(size 0.3 0.6)
			(layers "F.Cu" "F.Mask" "F.Paste")
			(roundrect_rratio 0.25)
			(net 1293 "/DCDC/CARRIER_PWR_ON")
			(pinfunction "EN")
			(pintype "passive")
		)
		(pad "6" smd roundrect
			(at 0.747 -0.499)
			(size 0.3 0.6)
			(layers "F.Cu" "F.Mask" "F.Paste")
			(roundrect_rratio 0.25)
			(net 1232 "/DCDC/1V15_FB")
			(pinfunction "FB")
			(pintype "passive")
		)
	)
	(footprint "antmicro-footprints:R_0402_1005Metric"
		(layer "F.Cu")
		(at 232.540532 121.71 180)
		(descr "Resistor SMD 0402")
		(tags "resistor SMD 0402")
		(property "Reference" "R74"
			(at -1.122484 -0.772697 0)
			(layer "F.SilkS")
			(effects
				(font
					(size 0.7 0.7)
					(thickness 0.15)
				)
				(justify right top)
			)
		)
		(property "Value" "R_470R_0402"
			(at -1.011843 1.772046 0)
			(layer "F.Fab")
			(effects
				(font
					(size 0.7 0.7)
					(thickness 0.15)
				)
				(justify right top)
			)
		)
		(property "Datasheet" "https://www.bourns.com/docs/product-datasheets/cr.pdf"
			(at 0 0 0)
			(layer "F.Fab")
			(hide yes)
			(effects
				(font
					(size 1.27 1.27)
					(thickness 0.15)
				)
			)
		)
		(property "Description" "SMD Chip Resistor, 470 ohm, ± 1%, 62.5 mW, 0402 [1005 Metric], Thick Film, General Purpose"
			(at 0 0 0)
			(layer "F.Fab")
			(hide yes)
			(effects
				(font
					(size 1.27 1.27)
					(thickness 0.15)
				)
			)
		)
		(property "Manufacturer" "Bourns"
			(at 0 0 180)
			(unlocked yes)
			(layer "F.Fab")
			(hide yes)
			(effects
				(font
					(size 1 1)
					(thickness 0.15)
				)
			)
		)
		(property "MPN" "CR0402-FX-4700GLF"
			(at 0 0 180)
			(unlocked yes)
			(layer "F.Fab")
			(hide yes)
			(effects
				(font
					(size 1 1)
					(thickness 0.15)
				)
			)
		)
		(property "Val" "470R"
			(at 0 0 180)
			(unlocked yes)
			(layer "F.Fab")
			(hide yes)
			(effects
				(font
					(size 1 1)
					(thickness 0.15)
				)
			)
		)
		(property "License" "Apache-2.0"
			(at 0 0 180)
			(unlocked yes)
			(layer "F.Fab")
			(hide yes)
			(effects
				(font
					(size 1 1)
					(thickness 0.15)
				)
			)
		)
		(property "Author" "Antmicro"
			(at 0 0 180)
			(unlocked yes)
			(layer "F.Fab")
			(hide yes)
			(effects
				(font
					(size 1 1)
					(thickness 0.15)
				)
			)
		)
		(property "Tolerance" "1%"
			(at 0 0 180)
			(unlocked yes)
			(layer "F.Fab")
			(hide yes)
			(effects
				(font
					(size 1 1)
					(thickness 0.15)
				)
			)
		)
		(sheetname "/USB Hub/")
		(sheetfile "usb_hub.kicad_sch")
		(attr smd)
		(fp_poly
			(pts
				(xy -0.925 -0.47) (xy 0.925 -0.47) (xy 0.925 0.47) (xy -0.925 0.47)
			)
			(stroke
				(width 0.05)
				(type default)
			)
			(fill no)
			(layer "F.CrtYd")
		)
		(fp_poly
			(pts
				(xy -0.5 -0.25) (xy 0.5 -0.25) (xy 0.5 0.25) (xy -0.5 0.25)
			)
			(stroke
				(width 0.15)
				(type solid)
			)
			(fill no)
			(layer "F.Fab")
		)
		(fp_text user "Author: Antmicro"
			(at -0.95 4.169 0)
			(layer "F.Fab")
			(effects
				(font
					(size 0.7 0.7)
					(thickness 0.15)
				)
				(justify right top)
			)
		)
		(fp_text user "${REFERENCE}"
			(at -0.95 3.168 0)
			(layer "F.Fab")
			(effects
				(font
					(size 0.7 0.7)
					(thickness 0.15)
				)
				(justify right top)
			)
		)
		(fp_text user "License: Apache-2.0"
			(at -0.949999 5.169 0)
			(layer "F.Fab")
			(effects
				(font
					(size 0.7 0.7)
					(thickness 0.15)
				)
				(justify right top)
			)
		)
		(pad "1" smd roundrect
			(at -0.48 0 180)
			(size 0.59 0.64)
			(layers "F.Cu" "F.Mask" "F.Paste")
			(roundrect_rratio 0.25)
			(net 1389 "Net-(D47-A)")
			(pintype "passive")
		)
		(pad "2" smd roundrect
			(at 0.48 0 180)
			(size 0.59 0.64)
			(layers "F.Cu" "F.Mask" "F.Paste")
			(roundrect_rratio 0.25)
			(net 71 "/USB Hub/USBC3_VBUS")
			(pintype "passive")
		)
	)
	(footprint "antmicro-footprints:C_0402_1005Metric"
		(layer "F.Cu")
		(at 157.37 144.95)
		(descr "Capacitor SMD 0402")
		(tags "capacitor SMD 0402")
		(property "Reference" "C202"
			(at -1.54 -3.85 0)
			(layer "F.SilkS")
			(effects
				(font
					(size 0.7 0.7)
					(thickness 0.15)
				)
				(justify left bottom)
			)
		)
		(property "Value" "C_100n_0402"
			(at -1.022927 2.155213 0)
			(layer "F.Fab")
			(effects
				(font
					(size 0.7 0.7)
					(thickness 0.15)
				)
				(justify left bottom)
			)
		)
		(property "Datasheet" "https://www.murata.com/products/productdetail?partno=GRM155R61H104KE14%23"
			(at 0 0 0)
			(layer "F.Fab")
			(hide yes)
			(effects
				(font
					(size 1.27 1.27)
					(thickness 0.15)
				)
			)
		)
		(property "Description" "SMD Multilayer Ceramic Capacitor, 0.1 µF, 50 V, 0402 [1005 Metric], ± 10%, X5R, GRM Series"
			(at 0 0 0)
			(layer "F.Fab")
			(hide yes)
			(effects
				(font
					(size 1.27 1.27)
					(thickness 0.15)
				)
			)
		)
		(property "Manufacturer" "Murata"
			(at 0 0 0)
			(unlocked yes)
			(layer "F.Fab")
			(hide yes)
			(effects
				(font
					(size 1 1)
					(thickness 0.15)
				)
			)
		)
		(property "MPN" "GRM155R61H104KE14D"
			(at 0 0 0)
			(unlocked yes)
			(layer "F.Fab")
			(hide yes)
			(effects
				(font
					(size 1 1)
					(thickness 0.15)
				)
			)
		)
		(property "Val" "100n"
			(at 0 0 0)
			(unlocked yes)
			(layer "F.Fab")
			(hide yes)
			(effects
				(font
					(size 1 1)
					(thickness 0.15)
				)
			)
		)
		(property "License" "Apache-2.0"
			(at 0 0 0)
			(unlocked yes)
			(layer "F.Fab")
			(hide yes)
			(effects
				(font
					(size 1 1)
					(thickness 0.15)
				)
			)
		)
		(property "Author" "Antmicro"
			(at 0 0 0)
			(unlocked yes)
			(layer "F.Fab")
			(hide yes)
			(effects
				(font
					(size 1 1)
					(thickness 0.15)
				)
			)
		)
		(property "Voltage" "50V"
			(at 0 0 0)
			(unlocked yes)
			(layer "F.Fab")
			(hide yes)
			(effects
				(font
					(size 1 1)
					(thickness 0.15)
				)
			)
		)
		(property "Dielectric" "X5R"
			(at 0 0 0)
			(unlocked yes)
			(layer "F.Fab")
			(hide yes)
			(effects
				(font
					(size 1 1)
					(thickness 0.15)
				)
			)
		)
		(sheetname "/Peripherals/")
		(sheetfile "peripherals.kicad_sch")
		(attr smd)
		(fp_rect
			(start -0.925 -0.47)
			(end 0.925 0.47)
			(stroke
				(width 0.05)
				(type default)
			)
			(fill no)
			(layer "F.CrtYd")
		)
		(fp_line
			(start -0.494 -0.25)
			(end 0.504 -0.25)
			(stroke
				(width 0.15)
				(type solid)
			)
			(layer "F.Fab")
		)
		(fp_line
			(start -0.494 0.248)
			(end -0.494 -0.25)
			(stroke
				(width 0.15)
				(type solid)
			)
			(layer "F.Fab")
		)
		(fp_line
			(start 0.504 -0.25)
			(end 0.504 0.248)
			(stroke
				(width 0.15)
				(type solid)
			)
			(layer "F.Fab")
		)
		(fp_line
			(start 0.504 0.248)
			(end -0.494 0.248)
			(stroke
				(width 0.15)
				(type solid)
			)
			(layer "F.Fab")
		)
		(fp_text user "${REFERENCE}"
			(at -0.939 4.599 0)
			(layer "F.Fab")
			(effects
				(font
					(size 0.7 0.7)
					(thickness 0.15)
				)
				(justify left bottom)
			)
		)
		(fp_text user "Author: Antmicro"
			(at -0.939 3.399 0)
			(layer "F.Fab")
			(effects
				(font
					(size 0.7 0.7)
					(thickness 0.15)
				)
				(justify left bottom)
			)
		)
		(fp_text user "License: Apache-2.0"
			(at -0.939 5.799 0)
			(layer "F.Fab")
			(effects
				(font
					(size 0.7 0.7)
					(thickness 0.15)
				)
				(justify left bottom)
			)
		)
		(pad "1" smd roundrect
			(at -0.48 0)
			(size 0.59 0.64)
			(layers "F.Cu" "F.Mask" "F.Paste")
			(roundrect_rratio 0.25)
			(net 1 "GND")
			(pintype "passive")
		)
		(pad "2" smd roundrect
			(at 0.48 0)
			(size 0.59 0.64)
			(layers "F.Cu" "F.Mask" "F.Paste")
			(roundrect_rratio 0.25)
			(net 11 "+1V8")
			(pintype "passive")
		)
	)
)
